(kicad_pcb
	(version 20221018)
	(generator pcbnew)
	(general
    (thickness 1.7403)
  )
	(paper "A4")
	(title_block
    (title "Data Center RDIMM DDR4 Tester")
    (date "2024-09-30")
    (rev "1.2.4")
		(comment 9 "footprint 168 of 690 (U15), pads 268-351 of 676")
	)
	(layers
    (0 "F.Cu" signal)
    (1 "In1.Cu" power)
    (2 "In2.Cu" signal)
    (3 "In3.Cu" power)
    (4 "In4.Cu" power)
    (5 "In5.Cu" signal)
    (6 "In6.Cu" power)
    (7 "In7.Cu" signal)
    (8 "In8.Cu" power)
    (9 "In9.Cu" signal)
    (10 "In10.Cu" power)
    (31 "B.Cu" signal)
    (32 "B.Adhes" user "B.Adhesive")
    (33 "F.Adhes" user "F.Adhesive")
    (34 "B.Paste" user)
    (35 "F.Paste" user)
    (36 "B.SilkS" user "B.Silkscreen")
    (37 "F.SilkS" user "F.Silkscreen")
    (38 "B.Mask" user)
    (39 "F.Mask" user)
    (40 "Dwgs.User" user "User.Drawings")
    (41 "Cmts.User" user "User.Comments")
    (42 "Eco1.User" user "User.Eco1")
    (43 "Eco2.User" user "User.Eco2")
    (44 "Edge.Cuts" user)
    (45 "Margin" user)
    (46 "B.CrtYd" user "B.Courtyard")
    (47 "F.CrtYd" user "F.Courtyard")
    (48 "B.Fab" user)
    (49 "F.Fab" user)
  )
	(footprint "data-center-rdimm-ddr4-tester-footprints:BGA-676_27x27mm_Layout26x26_P1X1mm"
    (layer "F.Cu")
    (at 183.635 90.06 180)
    (descr "FPGA XC7K160TFBG676")
    (tags "FPGA XC7K160TFBG676")
    (property "Author" "Antmicro")
    (property "License" "Apache-2.0")
    (property "MPN" "XC7K160T-FFG676")
    (property "Manufacturer" "AMD-Xilinx")
    (property "Sheetfile" "config-spi.kicad_sch")
    (property "Sheetname" "Config SPI flash")
    (property "ki_description" "Kintex®-7 Field Programmable Gate Array (FPGA) IC 300 4976640 65600 676-BBGA, FCBGA")
    (property "ki_keywords" "SMT, MICROCONTROLLER, IC, FPGA")
    (attr smd)
    (fp_text reference "U15" (at -10.675 -14.7 180) (layer "F.SilkS")
        (effects (font (size 0.7 0.7) (thickness 0.15)) (justify left bottom))
    )
    (fp_text value "XC7K160T-FFG676" (at 0 15.5 180) (layer "F.Fab")
        (effects (font (size 0.7 0.7) (thickness 0.15)) (justify left bottom))
    )
    (pad "E8" smd circle (at -5.5 -8.5 180) (size 0.5 0.5) (layers "F.Cu" "F.Paste" "F.Mask")
      (net 144 "1V8_SYS") (pinfunction "VCCBATT_0") (pintype "power_in"))
    (pad "E9" smd circle (at -4.5 -8.5 180) (size 0.5 0.5) (layers "F.Cu" "F.Paste" "F.Mask")
      (net 143 "3V3_SYS") (pinfunction "VCCO_16") (pintype "passive"))
    (pad "E10" smd circle (at -3.5 -8.5 180) (size 0.5 0.5) (layers "F.Cu" "F.Paste" "F.Mask")
      (net 83 "SD_DAT0") (pinfunction "IO_L12P_T1_MRCC_16") (pintype "bidirectional") (die_length 17.165))
    (pad "E11" smd circle (at -2.5 -8.5 180) (size 0.5 0.5) (layers "F.Cu" "F.Paste" "F.Mask")
      (net 733 "unconnected-(U15E-IO_L14P_T2_SRCC_16-PadE11)") (pinfunction "IO_L14P_T2_SRCC_16") (pintype "bidirectional+no_connect") (die_length 15.195))
    (pad "E12" smd circle (at -1.5 -8.5 180) (size 0.5 0.5) (layers "F.Cu" "F.Paste" "F.Mask")
      (net 734 "unconnected-(U15E-IO_L18N_T2_16-PadE12)") (pinfunction "IO_L18N_T2_16") (pintype "bidirectional+no_connect") (die_length 14.446))
    (pad "E13" smd circle (at -0.5 -8.5 180) (size 0.5 0.5) (layers "F.Cu" "F.Paste" "F.Mask")
      (net 735 "unconnected-(U15E-IO_L18P_T2_16-PadE13)") (pinfunction "IO_L18P_T2_16") (pintype "bidirectional+no_connect") (die_length 14.156))
    (pad "E14" smd circle (at 0.499 -8.5 180) (size 0.5 0.5) (layers "F.Cu" "F.Paste" "F.Mask")
      (net 9 "GND") (pinfunction "GND") (pintype "passive"))
    (pad "E15" smd circle (at 1.499 -8.5 180) (size 0.5 0.5) (layers "F.Cu" "F.Paste" "F.Mask")
      (net 448 "FMC_IO_10_P") (pinfunction "IO_L10P_T1_AD4P_15") (pintype "bidirectional") (die_length 18.592))
    (pad "E16" smd circle (at 2.499 -8.5 180) (size 0.5 0.5) (layers "F.Cu" "F.Paste" "F.Mask")
      (net 456 "FMC_IO_10_N") (pinfunction "IO_L10N_T1_AD4N_15") (pintype "bidirectional") (die_length 18.741))
    (pad "E17" smd circle (at 3.499 -8.5 180) (size 0.5 0.5) (layers "F.Cu" "F.Paste" "F.Mask")
      (net 457 "FMC_IO_12_N") (pinfunction "IO_L12N_T1_MRCC_AD5N_15") (pintype "bidirectional") (die_length 14.038))
    (pad "E18" smd circle (at 4.499 -8.5 180) (size 0.5 0.5) (layers "F.Cu" "F.Paste" "F.Mask")
      (net 458 "FMC_IO_13_P") (pinfunction "IO_L13P_T2_MRCC_15") (pintype "bidirectional") (die_length 17.01))
    (pad "E19" smd circle (at 5.499 -8.5 180) (size 0.5 0.5) (layers "F.Cu" "F.Paste" "F.Mask")
      (net 143 "3V3_SYS") (pinfunction "VCCO_15") (pintype "passive"))
    (pad "E20" smd circle (at 6.499 -8.5 180) (size 0.5 0.5) (layers "F.Cu" "F.Paste" "F.Mask")
      (net 459 "FMC_IO_17_N") (pinfunction "IO_L17N_T2_A25_15") (pintype "bidirectional") (die_length 13.703))
    (pad "E21" smd circle (at 7.499 -8.5 180) (size 0.5 0.5) (layers "F.Cu" "F.Paste" "F.Mask")
      (net 788 "HOT_SWAP_RED") (pinfunction "IO_L9P_T1_DQS_14") (pintype "bidirectional") (die_length 20.497))
    (pad "E22" smd circle (at 8.499 -8.5 180) (size 0.5 0.5) (layers "F.Cu" "F.Paste" "F.Mask")
      (net 74 "USR_LED5") (pinfunction "IO_L9N_T1_DQS_D13_14") (pintype "bidirectional") (die_length 20.469))
    (pad "E23" smd circle (at 9.499 -8.5 180) (size 0.5 0.5) (layers "F.Cu" "F.Paste" "F.Mask")
      (net 751 "PRSNT_M2C") (pinfunction "IO_L12N_T1_MRCC_14") (pintype "bidirectional") (die_length 19.664))
    (pad "E24" smd circle (at 10.499 -8.5 180) (size 0.5 0.5) (layers "F.Cu" "F.Paste" "F.Mask")
      (net 9 "GND") (pinfunction "GND") (pintype "passive"))
    (pad "E25" smd circle (at 11.499 -8.5 180) (size 0.5 0.5) (layers "F.Cu" "F.Paste" "F.Mask")
      (net 358 "SCL_3V3") (pinfunction "IO_L15P_T2_DQS_RDWR_B_14") (pintype "bidirectional") (die_length 20.423))
    (pad "E26" smd circle (at 12.499 -8.5 180) (size 0.5 0.5) (layers "F.Cu" "F.Paste" "F.Mask")
      (net 137 "UART0_TX") (pinfunction "IO_L17N_T2_A13_D29_14") (pintype "bidirectional") (die_length 20.928))
    (pad "F1" smd circle (at -12.5 -7.5 180) (size 0.5 0.5) (layers "F.Cu" "F.Paste" "F.Mask")
      (net 463 "GTX_TX3_N") (pinfunction "MGTXTXN0_116") (pintype "bidirectional") (die_length 14.583))
    (pad "F2" smd circle (at -11.5 -7.5 180) (size 0.5 0.5) (layers "F.Cu" "F.Paste" "F.Mask")
      (net 450 "GTX_TX3_P") (pinfunction "MGTXTXP0_116") (pintype "bidirectional") (die_length 14.603))
    (pad "F3" smd circle (at -10.5 -7.5 180) (size 0.5 0.5) (layers "F.Cu" "F.Paste" "F.Mask")
      (net 9 "GND") (pinfunction "GND") (pintype "passive"))
    (pad "F4" smd circle (at -9.5 -7.5 180) (size 0.5 0.5) (layers "F.Cu" "F.Paste" "F.Mask")
      (net 9 "GND") (pinfunction "GND") (pintype "passive"))
    (pad "F5" smd circle (at -8.5 -7.5 180) (size 0.5 0.5) (layers "F.Cu" "F.Paste" "F.Mask")
      (net 888 "/FPGA banks 115-116/GTR_REFCLK3_N") (pinfunction "MGTREFCLK1N_116") (pintype "bidirectional") (die_length 12.724))
    (pad "F6" smd circle (at -7.5 -7.5 180) (size 0.5 0.5) (layers "F.Cu" "F.Paste" "F.Mask")
      (net 887 "/FPGA banks 115-116/GTR_REFCLK3_P") (pinfunction "MGTREFCLK1P_116") (pintype "bidirectional") (die_length 13.203))
    (pad "F7" smd circle (at -6.5 -7.5 180) (size 0.5 0.5) (layers "F.Cu" "F.Paste" "F.Mask")
      (net 9 "GND") (pinfunction "GND") (pintype "passive"))
    (pad "F8" smd circle (at -5.5 -7.5 180) (size 0.5 0.5) (layers "F.Cu" "F.Paste" "F.Mask")
      (net 82 "SD_DAT1") (pinfunction "IO_L7N_T1_16") (pintype "bidirectional") (die_length 17.801))
    (pad "F9" smd circle (at -4.5 -7.5 180) (size 0.5 0.5) (layers "F.Cu" "F.Paste" "F.Mask")
      (net 88 "SD_CD") (pinfunction "IO_L7P_T1_16") (pintype "bidirectional") (die_length 16.924))
    (pad "F10" smd circle (at -3.5 -7.5 180) (size 0.5 0.5) (layers "F.Cu" "F.Paste" "F.Mask")
      (net 742 "unconnected-(U15E-IO_L11N_T1_SRCC_16-PadF10)") (pinfunction "IO_L11N_T1_SRCC_16") (pintype "bidirectional+no_connect") (die_length 15.436))
    (pad "F11" smd circle (at -2.5 -7.5 180) (size 0.5 0.5) (layers "F.Cu" "F.Paste" "F.Mask")
      (net 9 "GND") (pinfunction "GND") (pintype "passive"))
    (pad "F12" smd circle (at -1.5 -7.5 180) (size 0.5 0.5) (layers "F.Cu" "F.Paste" "F.Mask")
      (net 743 "unconnected-(U15E-IO_L16N_T2_16-PadF12)") (pinfunction "IO_L16N_T2_16") (pintype "bidirectional+no_connect") (die_length 13.211))
    (pad "F13" smd circle (at -0.5 -7.5 180) (size 0.5 0.5) (layers "F.Cu" "F.Paste" "F.Mask")
      (net 744 "unconnected-(U15E-IO_L15N_T2_DQS_16-PadF13)") (pinfunction "IO_L15N_T2_DQS_16") (pintype "bidirectional+no_connect") (die_length 15.248))
    (pad "F14" smd circle (at 0.499 -7.5 180) (size 0.5 0.5) (layers "F.Cu" "F.Paste" "F.Mask")
      (net 745 "unconnected-(U15E-IO_L15P_T2_DQS_16-PadF14)") (pinfunction "IO_L15P_T2_DQS_16") (pintype "bidirectional+no_connect") (die_length 15.557))
    (pad "F15" smd circle (at 1.499 -7.5 180) (size 0.5 0.5) (layers "F.Cu" "F.Paste" "F.Mask")
      (net 460 "FMC_IO_8_N") (pinfunction "IO_L8N_T1_AD3N_15") (pintype "bidirectional") (die_length 18.872))
    (pad "F16" smd circle (at 2.499 -7.5 180) (size 0.5 0.5) (layers "F.Cu" "F.Paste" "F.Mask")
      (net 143 "3V3_SYS") (pinfunction "VCCO_15") (pintype "passive"))
    (pad "F17" smd circle (at 3.499 -7.5 180) (size 0.5 0.5) (layers "F.Cu" "F.Paste" "F.Mask")
      (net 472 "FMC_IO_12_P") (pinfunction "IO_L12P_T1_MRCC_AD5P_15") (pintype "bidirectional") (die_length 13.832))
    (pad "F18" smd circle (at 4.499 -7.5 180) (size 0.5 0.5) (layers "F.Cu" "F.Paste" "F.Mask")
      (net 473 "FMC_IO_11_N") (pinfunction "IO_L11N_T1_SRCC_AD12N_15") (pintype "bidirectional") (die_length 12.908))
    (pad "F19" smd circle (at 5.499 -7.5 180) (size 0.5 0.5) (layers "F.Cu" "F.Paste" "F.Mask")
      (net 474 "FMC_IO_17_P") (pinfunction "IO_L17P_T2_A26_15") (pintype "bidirectional") (die_length 14.191))
    (pad "F20" smd circle (at 6.499 -7.5 180) (size 0.5 0.5) (layers "F.Cu" "F.Paste" "F.Mask")
      (net 475 "FMC_IO_16_N") (pinfunction "IO_L16N_T2_A27_15") (pintype "bidirectional") (die_length 12.487))
    (pad "F21" smd circle (at 7.499 -7.5 180) (size 0.5 0.5) (layers "F.Cu" "F.Paste" "F.Mask")
      (net 9 "GND") (pinfunction "GND") (pintype "passive"))
    (pad "F22" smd circle (at 8.499 -7.5 180) (size 0.5 0.5) (layers "F.Cu" "F.Paste" "F.Mask")
      (net 746 "unconnected-(U15C-IO_L12P_T1_MRCC_14-PadF22)") (pinfunction "IO_L12P_T1_MRCC_14") (pintype "bidirectional+no_connect") (die_length 19.515))
    (pad "F23" smd circle (at 9.499 -7.5 180) (size 0.5 0.5) (layers "F.Cu" "F.Paste" "F.Mask")
      (net 747 "unconnected-(U15C-IO_L13N_T2_MRCC_14-PadF23)") (pinfunction "IO_L13N_T2_MRCC_14") (pintype "bidirectional+no_connect") (die_length 17.933))
    (pad "F24" smd circle (at 10.499 -7.5 180) (size 0.5 0.5) (layers "F.Cu" "F.Paste" "F.Mask")
      (net 449 "CLK_DIR") (pinfunction "IO_L14N_T2_SRCC_14") (pintype "bidirectional") (die_length 19.105))
    (pad "F25" smd circle (at 11.499 -7.5 180) (size 0.5 0.5) (layers "F.Cu" "F.Paste" "F.Mask")
      (net 135 "UART0_RX") (pinfunction "IO_L17P_T2_A14_D30_14") (pintype "bidirectional") (die_length 19.892))
    (pad "F26" smd circle (at 12.499 -7.5 180) (size 0.5 0.5) (layers "F.Cu" "F.Paste" "F.Mask")
      (net 143 "3V3_SYS") (pinfunction "VCCO_14") (pintype "passive"))
    (pad "G1" smd circle (at -12.5 -6.5 180) (size 0.5 0.5) (layers "F.Cu" "F.Paste" "F.Mask")
      (net 9 "GND") (pinfunction "GND") (pintype "passive"))
    (pad "G2" smd circle (at -11.5 -6.5 180) (size 0.5 0.5) (layers "F.Cu" "F.Paste" "F.Mask")
      (net 306 "1V2_SYS") (pinfunction "MGTAVTT") (pintype "passive"))
    (pad "G3" smd circle (at -10.5 -6.5 180) (size 0.5 0.5) (layers "F.Cu" "F.Paste" "F.Mask")
      (net 637 "GTX_RX3_N") (pinfunction "MGTXRXN0_116") (pintype "bidirectional") (die_length 12.486))
    (pad "G4" smd circle (at -9.5 -6.5 180) (size 0.5 0.5) (layers "F.Cu" "F.Paste" "F.Mask")
      (net 636 "GTX_RX3_P") (pinfunction "MGTXRXP0_116") (pintype "bidirectional") (die_length 12.584))
    (pad "G5" smd circle (at -8.5 -6.5 180) (size 0.5 0.5) (layers "F.Cu" "F.Paste" "F.Mask")
      (net 9 "GND") (pinfunction "GND") (pintype "passive"))
    (pad "G6" smd circle (at -7.5 -6.5 180) (size 0.5 0.5) (layers "F.Cu" "F.Paste" "F.Mask")
      (net 147 "1V0_SYS") (pinfunction "MGTAVCC") (pintype "passive"))
    (pad "G7" smd circle (at -6.5 -6.5 180) (size 0.5 0.5) (layers "F.Cu" "F.Paste" "F.Mask")
      (net 93 "INIT_B") (pinfunction "INIT_B_0") (pintype "bidirectional") (die_length 30.602))
    (pad "G8" smd circle (at -5.5 -6.5 180) (size 0.5 0.5) (layers "F.Cu" "F.Paste" "F.Mask")
      (net 9 "GND") (pinfunction "GND") (pintype "passive"))
    (pad "G9" smd circle (at -4.5 -6.5 180) (size 0.5 0.5) (layers "F.Cu" "F.Paste" "F.Mask")
      (net 748 "unconnected-(U15E-IO_L2N_T0_16-PadG9)") (pinfunction "IO_L2N_T0_16") (pintype "bidirectional+no_connect") (die_length 14.946))
    (pad "G10" smd circle (at -3.5 -6.5 180) (size 0.5 0.5) (layers "F.Cu" "F.Paste" "F.Mask")
      (net 749 "unconnected-(U15E-IO_L2P_T0_16-PadG10)") (pinfunction "IO_L2P_T0_16") (pintype "bidirectional+no_connect") (die_length 13.481))
    (pad "G11" smd circle (at -2.5 -6.5 180) (size 0.5 0.5) (layers "F.Cu" "F.Paste" "F.Mask")
      (net 750 "unconnected-(U15E-IO_L11P_T1_SRCC_16-PadG11)") (pinfunction "IO_L11P_T1_SRCC_16") (pintype "bidirectional+no_connect") (die_length 14.905))
    (pad "G12" smd circle (at -1.5 -6.5 180) (size 0.5 0.5) (layers "F.Cu" "F.Paste" "F.Mask")
      (net 752 "unconnected-(U15E-IO_L16P_T2_16-PadG12)") (pinfunction "IO_L16P_T2_16") (pintype "bidirectional+no_connect") (die_length 13.211))
    (pad "G13" smd circle (at -0.5 -6.5 180) (size 0.5 0.5) (layers "F.Cu" "F.Paste" "F.Mask")
      (net 143 "3V3_SYS") (pinfunction "VCCO_16") (pintype "passive"))
    (pad "G14" smd circle (at 0.499 -6.5 180) (size 0.5 0.5) (layers "F.Cu" "F.Paste" "F.Mask")
      (net 753 "unconnected-(U15E-IO_L5N_T0_16-PadG14)") (pinfunction "IO_L5N_T0_16") (pintype "bidirectional+no_connect") (die_length 10.327))
    (pad "G15" smd circle (at 1.499 -6.5 180) (size 0.5 0.5) (layers "F.Cu" "F.Paste" "F.Mask")
      (net 476 "FMC_IO_8_P") (pinfunction "IO_L8P_T1_AD3P_15") (pintype "bidirectional") (die_length 19.124))
    (pad "G16" smd circle (at 2.499 -6.5 180) (size 0.5 0.5) (layers "F.Cu" "F.Paste" "F.Mask")
      (net 490 "FMC_IO_7_N") (pinfunction "IO_L7N_T1_AD10N_15") (pintype "bidirectional") (die_length 13.719))
    (pad "G17" smd circle (at 3.499 -6.5 180) (size 0.5 0.5) (layers "F.Cu" "F.Paste" "F.Mask")
      (net 491 "FMC_IO_11_P") (pinfunction "IO_L11P_T1_SRCC_AD12P_15") (pintype "bidirectional") (die_length 12.537))
    (pad "G18" smd circle (at 4.499 -6.5 180) (size 0.5 0.5) (layers "F.Cu" "F.Paste" "F.Mask")
      (net 9 "GND") (pinfunction "GND") (pintype "passive"))
    (pad "G19" smd circle (at 5.499 -6.5 180) (size 0.5 0.5) (layers "F.Cu" "F.Paste" "F.Mask")
      (net 492 "FMC_IO_16_P") (pinfunction "IO_L16P_T2_A28_15") (pintype "bidirectional") (die_length 12.445))
    (pad "G20" smd circle (at 6.499 -6.5 180) (size 0.5 0.5) (layers "F.Cu" "F.Paste" "F.Mask")
      (net 493 "FMC_IO_18_N") (pinfunction "IO_L18N_T2_A23_15") (pintype "bidirectional") (die_length 11.544))
    (pad "G21" smd circle (at 7.499 -6.5 180) (size 0.5 0.5) (layers "F.Cu" "F.Paste" "F.Mask")
      (net 758 "unconnected-(U15C-IO_L19N_T3_A09_D25_VREF_14-PadG21)") (pinfunction "IO_L19N_T3_A09_D25_VREF_14") (pintype "bidirectional+no_connect") (die_length 18.813))
    (pad "G22" smd circle (at 8.499 -6.5 180) (size 0.5 0.5) (layers "F.Cu" "F.Paste" "F.Mask")
      (net 759 "unconnected-(U15C-IO_L13P_T2_MRCC_14-PadG22)") (pinfunction "IO_L13P_T2_MRCC_14") (pintype "bidirectional+no_connect") (die_length 18.389))
    (pad "G23" smd circle (at 9.499 -6.5 180) (size 0.5 0.5) (layers "F.Cu" "F.Paste" "F.Mask")
      (net 143 "3V3_SYS") (pinfunction "VCCO_14") (pintype "passive"))
    (pad "G24" smd circle (at 10.499 -6.5 180) (size 0.5 0.5) (layers "F.Cu" "F.Paste" "F.Mask")
      (net 908 "FMC_SDA_3V3") (pinfunction "IO_L14P_T2_SRCC_14") (pintype "bidirectional") (die_length 19.02))
    (pad "G25" smd circle (at 11.499 -6.5 180) (size 0.5 0.5) (layers "F.Cu" "F.Paste" "F.Mask")
      (net 133 "AUX_JTAG_RST") (pinfunction "IO_L16P_T2_CSI_B_14") (pintype "bidirectional") (die_length 19.777))
    (pad "G26" smd circle (at 12.499 -6.5 180) (size 0.5 0.5) (layers "F.Cu" "F.Paste" "F.Mask")
      (net 804 "FPGA_POWER_CYCLE") (pinfunction "IO_L16N_T2_A15_D31_14") (pintype "bidirectional") (die_length 19.839))
    (pad "H1" smd circle (at -12.5 -5.5 180) (size 0.5 0.5) (layers "F.Cu" "F.Paste" "F.Mask")
      (net 479 "GTX_TX4_N") (pinfunction "MGTXTXN3_115") (pintype "bidirectional") (die_length 13.778))
    (pad "H2" smd circle (at -11.5 -5.5 180) (size 0.5 0.5) (layers "F.Cu" "F.Paste" "F.Mask")
      (net 465 "GTX_TX4_P") (pinfunction "MGTXTXP3_115") (pintype "bidirectional") (die_length 13.817))
    (pad "H3" smd circle (at -10.5 -5.5 180) (size 0.5 0.5) (layers "F.Cu" "F.Paste" "F.Mask")
      (net 306 "1V2_SYS") (pinfunction "MGTAVTT") (pintype "passive"))
    (pad "H4" smd circle (at -9.5 -5.5 180) (size 0.5 0.5) (layers "F.Cu" "F.Paste" "F.Mask")
      (net 9 "GND") (pinfunction "GND") (pintype "passive"))
    (pad "H5" smd circle (at -8.5 -5.5 180) (size 0.5 0.5) (layers "F.Cu" "F.Paste" "F.Mask")
      (net 409 "/FPGA banks 115-116/GTR_REFCLK0_N") (pinfunction "MGTREFCLK0N_115") (pintype "bidirectional") (die_length 11.598))
    (pad "H6" smd circle (at -7.5 -5.5 180) (size 0.5 0.5) (layers "F.Cu" "F.Paste" "F.Mask")
      (net 404 "/FPGA banks 115-116/GTR_REFCLK0_P") (pinfunction "MGTREFCLK0P_115") (pintype "bidirectional") (die_length 11.559))
    (pad "H7" smd circle (at -6.5 -5.5 180) (size 0.5 0.5) (layers "F.Cu" "F.Paste" "F.Mask")
      (net 9 "GND") (pinfunction "GND") (pintype "passive"))
    (pad "H8" smd circle (at -5.5 -5.5 180) (size 0.5 0.5) (layers "F.Cu" "F.Paste" "F.Mask")
      (net 760 "unconnected-(U15E-IO_L1N_T0_16-PadH8)") (pinfunction "IO_L1N_T0_16") (pintype "bidirectional+no_connect") (die_length 16.747))
    (pad "H9" smd circle (at -4.5 -5.5 180) (size 0.5 0.5) (layers "F.Cu" "F.Paste" "F.Mask")
      (net 761 "unconnected-(U15E-IO_L1P_T0_16-PadH9)") (pinfunction "IO_L1P_T0_16") (pintype "bidirectional+no_connect") (die_length 15.601))
    (pad "H10" smd circle (at -3.5 -5.5 180) (size 0.5 0.5) (layers "F.Cu" "F.Paste" "F.Mask")
      (net 143 "3V3_SYS") (pinfunction "VCCO_16") (pintype "passive"))
    (pad "H11" smd circle (at -2.5 -5.5 180) (size 0.5 0.5) (layers "F.Cu" "F.Paste" "F.Mask")
      (net 762 "unconnected-(U15E-IO_L6N_T0_VREF_16-PadH11)") (pinfunction "IO_L6N_T0_VREF_16") (pintype "bidirectional+no_connect") (die_length 14.821))
    (pad "H12" smd circle (at -1.5 -5.5 180) (size 0.5 0.5) (layers "F.Cu" "F.Paste" "F.Mask")
      (net 763 "unconnected-(U15E-IO_L6P_T0_16-PadH12)") (pinfunction "IO_L6P_T0_16") (pintype "bidirectional+no_connect") (die_length 13.516))
    (pad "H13" smd circle (at -0.5 -5.5 180) (size 0.5 0.5) (layers "F.Cu" "F.Paste" "F.Mask")
      (net 764 "unconnected-(U15E-IO_L3N_T0_DQS_16-PadH13)") (pinfunction "IO_L3N_T0_DQS_16") (pintype "bidirectional+no_connect") (die_length 12.402))
  )
)
